FILE_TYPE = MULTI_PHYS_TABLE;

PART 'CONN2_AAABAT029Y19'

{========================================================================================}
:VALUE                   | PART_TYPE | MATERIAL | PART_NUMBER       = STANDARD | LIFECYCLE | PART_NUMBER       | JEDEC_TYPE                  | DESCRIPTION                                    | MANUFTR | MANUF_PN          | RD_CMPLS_LVL | CMPLS_LVL | CLASS | DIP_SMD | FROM_PJ        | DATA                      | FP_ECN                | EE_CHECK_LIST | CREATOR | CREATEDAY  | PSL | STATUS | ESD_CDM | ESD_HBM | ESD_MM | MSD  | PIN_LENGTH_LONG_PIN | PIN_LENGTH_SHORT_PIN ;
{========================================================================================}
 'CONN2_AAA-BAT-029-Y19' | 'THLF'    | 'IO'     | 'DFHS02FR062'(!)  = ''       | ''        | 'DFHS02FR062'     |'BATTERY_AAA-BAT-029-Y19'| 'CONN DIP HOUSING 2P 1R FR(P20,H8.80)'         | 'LTS'   | 'AAA-BAT-029-Y19' | 'EP(V1)'     | 'EP(V1)'  | 'IO'  | 'DIP'   | 'S1L-LI-JYUAN' | 'LTS_AAA-BAT-029-Y19.pdf' | 'AAA-BAT-029-Y19.msg' | ''            | ''      | '20200909' | ''  | ''     | 'NA'    | 'NA'    | 'NA'   | 'NA' | '124 MILS'          | '124 MILS'          
 'CONN2_AAA-BAT-029-Y19' | 'THLF'    | 'EMPTY'  | 'DFHS02FR062'(!)  = ''       | ''        | 'DFHS02FR062'     |'BATTERY_AAA-BAT-029-Y19'| 'CONN DIP HOUSING 2P 1R FR(P20,H8.80)'         | 'LTS'   | 'AAA-BAT-029-Y19' | 'EP(V1)'     | 'EP(V1)'  | 'IO'  | 'DIP'   | 'S1L-LI-JYUAN' | 'LTS_AAA-BAT-029-Y19.pdf' | 'AAA-BAT-029-Y19.msg' | ''            | ''      | '20200909' | ''  | ''     | 'NA'    | 'NA'    | 'NA'   | 'NA' | '124 MILS'          | '124 MILS'          
 'CONN2_AAA-BAT-029-Y19' | 'THLF'    | 'IO'     | 'SP_DFHS02FR062'(!) = ''       | ''        | 'DFHS02FR062'     |'G_BATTERY_AAA-BAT-029-Y19'| 'CONN DIP HOUSING 2P 1R FR(P20,H8.80)_FOR SEL' | 'LTS'   | 'AAA-BAT-029-Y19' | 'EP(V1)'     | 'EP(V1)'  | 'IO'  | 'DIP'   | 'S8Z-VINCENT'  | 'LTS_AAA-BAT-029-Y19.pdf' | 'AAA-BAT-029-Y19.msg' | ''            | ''      | '20221201' | ''  | ''     | 'NA'    | 'NA'    | 'NA'   | 'NA' | '124 MILS'          | '124 MILS'          
 'CONN2_AAA-BAT-029-Y19' | 'THLF'    | 'EMPTY'  | 'SP_DFHS02FR062'(!) = ''       | ''        | 'DFHS02FR062'     |'G_BATTERY_AAA-BAT-029-Y19'| 'CONN DIP HOUSING 2P 1R FR(P20,H8.80)_FOR SEL' | 'LTS'   | 'AAA-BAT-029-Y19' | 'EP(V1)'     | 'EP(V1)'  | 'IO'  | 'DIP'   | 'S8Z-VINCENT'  | 'LTS_AAA-BAT-029-Y19.pdf' | 'AAA-BAT-029-Y19.msg' | ''            | ''      | '20221201' | ''  | ''     | 'NA'    | 'NA'    | 'NA'   | 'NA' | '124 MILS'          | '124 MILS'          
 'CONN2_AAA-BAT-029-Y19' | 'THLF'    | 'IO'     | 'DFHS02FR062SEL1'(!) = ''       | ''        | 'DFHS02FR062SEL1' |'G_BATTERY_AAA-BAT-029-Y19'| 'CONN DIP HS 2P 1R FR(P20,H8.80) SELA'         | 'LTS'   | 'AAA-BAT-029-Y19' | 'EP(V1)'     | 'EP(V1)'  | 'IO'  | 'DIP'   | 'S8Z-VINCENT'  | 'LTS_AAA-BAT-029-Y19.pdf' | 'AAA-BAT-029-Y19.msg' | ''            | ''      | '20221201' | ''  | ''     | 'NA'    | 'NA'    | 'NA'   | 'NA' | '124 MILS'          | '124 MILS'          
 'CONN2_AAA-BAT-029-Y19' | 'THLF'    | 'EMPTY'  | 'DFHS02FR062SEL1'(!) = ''       | ''        | 'DFHS02FR062SEL1' |'G_BATTERY_AAA-BAT-029-Y19'| 'CONN DIP HS 2P 1R FR(P20,H8.80) SELA'         | 'LTS'   | 'AAA-BAT-029-Y19' | 'EP(V1)'     | 'EP(V1)'  | 'IO'  | 'DIP'   | 'S8Z-VINCENT'  | 'LTS_AAA-BAT-029-Y19.pdf' | 'AAA-BAT-029-Y19.msg' | ''            | ''      | '20221201' | ''  | ''     | 'NA'    | 'NA'    | 'NA'   | 'NA' | '124 MILS'          | '124 MILS'          

END_PART

END.

